(kicad_pcb
	(version 20260206)
	(generator "pcbnew")
	(generator_version "10.0")
	(general
		(thickness 1.6)
		(legacy_teardrops no)
	)
	(paper "A4")
	(title_block
		(title "04192023_DAF0TMB3IC0_F0TG_MB_C_brd_V02_OCP.brd")
		(comment 1 "Grand Teton / footprints 2069-2075 of 8354")
	)
	(layers
		(0 "F.Cu" signal "TOP")
		(4 "In1.Cu" signal "GND")
		(6 "In2.Cu" signal "IN1")
		(8 "In3.Cu" signal "GND1")
		(10 "In4.Cu" signal "IN2")
		(12 "In5.Cu" signal "GND2")
		(14 "In6.Cu" signal "IN3")
		(16 "In7.Cu" signal "GND3")
		(18 "In8.Cu" signal "VCC")
		(20 "In9.Cu" signal "VCC1")
		(22 "In10.Cu" signal "GND4")
		(24 "In11.Cu" signal "IN4")
		(26 "In12.Cu" signal "GND5")
		(28 "In13.Cu" signal "IN5")
		(30 "In14.Cu" signal "GND6")
		(32 "In15.Cu" signal "IN6")
		(34 "In16.Cu" signal "GND7")
		(2 "B.Cu" signal "BOTTOM")
		(9 "F.Adhes" user "F.Adhesive")
		(11 "B.Adhes" user "B.Adhesive")
		(13 "F.Paste" user "Package Geometry/Pastemask Top")
		(15 "B.Paste" user "Package Geometry/Pastemask Bottom")
		(5 "F.SilkS" user "Ref Des/Silkscreen Top")
		(7 "B.SilkS" user "Ref Des/Silkscreen Bottom")
		(1 "F.Mask" user "Board Geometry/Soldermask Top")
		(3 "B.Mask" user "Board Geometry/Soldermask Bottom")
		(17 "Dwgs.User" user "User.Drawings")
		(19 "Cmts.User" user "User.Comments")
		(21 "Eco1.User" user "User.Eco1")
		(23 "Eco2.User" user "User.Eco2")
		(25 "Edge.Cuts" user "Board Geometry/Outline")
		(27 "Margin" user)
		(31 "F.CrtYd" user "Package Geometry/Place Bound Top")
		(29 "B.CrtYd" user "Package Geometry/Place Bound Bottom")
		(35 "F.Fab" user "Ref Des/Assembly Top")
		(33 "B.Fab" user "Ref Des/Assembly Bottom")
	)
	(footprint ""
		(layer "F.Cu")
		(at 359.7275 -172.50029)
		(property "Reference" "PC184"
			(at 0 0 0)
			(layer "F.SilkS")
			(hide yes)
			(effects
				(font
					(size 1.27 1.27)
				)
			)
		)
		(property "Value" ""
			(at 0 0 0)
			(layer "F.Fab")
			(effects
				(font
					(size 1.27 1.27)
				)
			)
		)
		(duplicate_pad_numbers_are_jumpers no)
		(fp_line
			(start -0.7874 -0.4064)
			(end 0.7874 -0.4064)
			(stroke
				(width 0.1524)
				(type default)
			)
			(layer "F.SilkS")
		)
		(fp_line
			(start -0.7874 0.4064)
			(end -0.7874 -0.4064)
			(stroke
				(width 0.1524)
				(type default)
			)
			(layer "F.SilkS")
		)
		(fp_line
			(start 0.7874 -0.4064)
			(end 0.7874 0.4064)
			(stroke
				(width 0.1524)
				(type default)
			)
			(layer "F.SilkS")
		)
		(fp_line
			(start 0.7874 0.4064)
			(end -0.7874 0.4064)
			(stroke
				(width 0.1524)
				(type default)
			)
			(layer "F.SilkS")
		)
		(fp_line
			(start -0.67945 -0.305054)
			(end -0.12065 -0.305054)
			(stroke
				(width 0.1)
				(type default)
			)
			(layer "F.Fab")
		)
		(fp_line
			(start -0.67945 0.3048)
			(end -0.67945 -0.305054)
			(stroke
				(width 0.1)
				(type default)
			)
			(layer "F.Fab")
		)
		(fp_line
			(start -0.12065 -0.305054)
			(end -0.12065 -0.2794)
			(stroke
				(width 0.1)
				(type default)
			)
			(layer "F.Fab")
		)
		(fp_line
			(start -0.12065 -0.2794)
			(end 0.12065 -0.2794)
			(stroke
				(width 0.1)
				(type default)
			)
			(layer "F.Fab")
		)
		(fp_line
			(start -0.12065 0.2794)
			(end -0.12065 0.3048)
			(stroke
				(width 0.1)
				(type default)
			)
			(layer "F.Fab")
		)
		(fp_line
			(start -0.12065 0.3048)
			(end -0.67945 0.3048)
			(stroke
				(width 0.1)
				(type default)
			)
			(layer "F.Fab")
		)
		(fp_line
			(start 0.120396 0.2794)
			(end -0.12065 0.2794)
			(stroke
				(width 0.1)
				(type default)
			)
			(layer "F.Fab")
		)
		(fp_line
			(start 0.120396 0.3048)
			(end 0.120396 0.2794)
			(stroke
				(width 0.1)
				(type default)
			)
			(layer "F.Fab")
		)
		(fp_line
			(start 0.12065 -0.3048)
			(end 0.67945 -0.3048)
			(stroke
				(width 0.1)
				(type default)
			)
			(layer "F.Fab")
		)
		(fp_line
			(start 0.12065 -0.2794)
			(end 0.12065 -0.3048)
			(stroke
				(width 0.1)
				(type default)
			)
			(layer "F.Fab")
		)
		(fp_line
			(start 0.67945 -0.3048)
			(end 0.67945 0.3048)
			(stroke
				(width 0.1)
				(type default)
			)
			(layer "F.Fab")
		)
		(fp_line
			(start 0.67945 0.3048)
			(end 0.120396 0.3048)
			(stroke
				(width 0.1)
				(type default)
			)
			(layer "F.Fab")
		)
		(pad "1" smd circle
			(at -0.40005 0)
			(size 0 0)
			(layers "F.Cu" "F.Mask" "F.Paste")
			(net "SW_PVDDCR_CPU0_P0_SW5")
		)
		(pad "2" smd circle
			(at 0.40005 0)
			(size 0 0)
			(layers "F.Cu" "F.Mask" "F.Paste")
			(net "SW_PVDDCR_CPU0_P0_SW5_RC")
		)
	)
	(footprint ""
		(layer "F.Cu")
		(at 145.773394 -54.913784 -90)
		(property "Reference" "C1505"
			(at 0 0 270)
			(layer "F.SilkS")
			(hide yes)
			(effects
				(font
					(size 1.27 1.27)
				)
			)
		)
		(property "Value" ""
			(at 0 0 270)
			(layer "F.Fab")
			(effects
				(font
					(size 1.27 1.27)
				)
			)
		)
		(duplicate_pad_numbers_are_jumpers no)
		(fp_line
			(start -0.7874 0.4064)
			(end -0.7874 -0.4064)
			(stroke
				(width 0.1524)
				(type default)
			)
			(layer "F.SilkS")
		)
		(fp_line
			(start 0.7874 0.4064)
			(end -0.7874 0.4064)
			(stroke
				(width 0.1524)
				(type default)
			)
			(layer "F.SilkS")
		)
		(fp_line
			(start -0.7874 -0.4064)
			(end 0.7874 -0.4064)
			(stroke
				(width 0.1524)
				(type default)
			)
			(layer "F.SilkS")
		)
		(fp_line
			(start 0.7874 -0.4064)
			(end 0.7874 0.4064)
			(stroke
				(width 0.1524)
				(type default)
			)
			(layer "F.SilkS")
		)
		(fp_line
			(start -0.67945 0.3048)
			(end -0.67945 -0.305054)
			(stroke
				(width 0.1)
				(type default)
			)
			(layer "F.Fab")
		)
		(fp_line
			(start -0.12065 0.3048)
			(end -0.67945 0.3048)
			(stroke
				(width 0.1)
				(type default)
			)
			(layer "F.Fab")
		)
		(fp_line
			(start 0.120396 0.3048)
			(end 0.120396 0.2794)
			(stroke
				(width 0.1)
				(type default)
			)
			(layer "F.Fab")
		)
		(fp_line
			(start 0.67945 0.3048)
			(end 0.120396 0.3048)
			(stroke
				(width 0.1)
				(type default)
			)
			(layer "F.Fab")
		)
		(fp_line
			(start -0.12065 0.2794)
			(end -0.12065 0.3048)
			(stroke
				(width 0.1)
				(type default)
			)
			(layer "F.Fab")
		)
		(fp_line
			(start 0.120396 0.2794)
			(end -0.12065 0.2794)
			(stroke
				(width 0.1)
				(type default)
			)
			(layer "F.Fab")
		)
		(fp_line
			(start -0.12065 -0.2794)
			(end 0.12065 -0.2794)
			(stroke
				(width 0.1)
				(type default)
			)
			(layer "F.Fab")
		)
		(fp_line
			(start 0.12065 -0.2794)
			(end 0.12065 -0.3048)
			(stroke
				(width 0.1)
				(type default)
			)
			(layer "F.Fab")
		)
		(fp_line
			(start 0.12065 -0.3048)
			(end 0.67945 -0.3048)
			(stroke
				(width 0.1)
				(type default)
			)
			(layer "F.Fab")
		)
		(fp_line
			(start 0.67945 -0.3048)
			(end 0.67945 0.3048)
			(stroke
				(width 0.1)
				(type default)
			)
			(layer "F.Fab")
		)
		(fp_line
			(start -0.67945 -0.305054)
			(end -0.12065 -0.305054)
			(stroke
				(width 0.1)
				(type default)
			)
			(layer "F.Fab")
		)
		(fp_line
			(start -0.12065 -0.305054)
			(end -0.12065 -0.2794)
			(stroke
				(width 0.1)
				(type default)
			)
			(layer "F.Fab")
		)
		(pad "1" smd circle
			(at -0.40005 0 270)
			(size 0 0)
			(layers "F.Cu" "F.Mask" "F.Paste")
			(net "PVDD18_S5_P0")
		)
		(pad "2" smd circle
			(at 0.40005 0 270)
			(size 0 0)
			(layers "F.Cu" "F.Mask" "F.Paste")
			(net "GND")
		)
	)
	(footprint ""
		(layer "F.Cu")
		(at 145.161 -119.761)
		(property "Reference" "R8125"
			(at 0 0 0)
			(layer "F.SilkS")
			(hide yes)
			(effects
				(font
					(size 1.27 1.27)
				)
			)
		)
		(property "Value" ""
			(at 0 0 0)
			(layer "F.Fab")
			(effects
				(font
					(size 1.27 1.27)
				)
			)
		)
		(duplicate_pad_numbers_are_jumpers no)
		(fp_line
			(start -0.7874 -0.4064)
			(end 0.7874 -0.4064)
			(stroke
				(width 0.1524)
				(type default)
			)
			(layer "F.SilkS")
		)
		(fp_line
			(start -0.7874 0.4064)
			(end -0.7874 -0.4064)
			(stroke
				(width 0.1524)
				(type default)
			)
			(layer "F.SilkS")
		)
		(fp_line
			(start 0.7874 -0.4064)
			(end 0.7874 0.4064)
			(stroke
				(width 0.1524)
				(type default)
			)
			(layer "F.SilkS")
		)
		(fp_line
			(start 0.7874 0.4064)
			(end -0.7874 0.4064)
			(stroke
				(width 0.1524)
				(type default)
			)
			(layer "F.SilkS")
		)
		(fp_line
			(start -0.67945 -0.305054)
			(end -0.12065 -0.305054)
			(stroke
				(width 0.1)
				(type default)
			)
			(layer "F.Fab")
		)
		(fp_line
			(start -0.67945 0.3048)
			(end -0.67945 -0.305054)
			(stroke
				(width 0.1)
				(type default)
			)
			(layer "F.Fab")
		)
		(fp_line
			(start -0.12065 -0.305054)
			(end -0.12065 -0.2794)
			(stroke
				(width 0.1)
				(type default)
			)
			(layer "F.Fab")
		)
		(fp_line
			(start -0.12065 -0.2794)
			(end 0.12065 -0.2794)
			(stroke
				(width 0.1)
				(type default)
			)
			(layer "F.Fab")
		)
		(fp_line
			(start -0.12065 0.2794)
			(end -0.12065 0.3048)
			(stroke
				(width 0.1)
				(type default)
			)
			(layer "F.Fab")
		)
		(fp_line
			(start -0.12065 0.3048)
			(end -0.67945 0.3048)
			(stroke
				(width 0.1)
				(type default)
			)
			(layer "F.Fab")
		)
		(fp_line
			(start 0.120396 0.2794)
			(end -0.12065 0.2794)
			(stroke
				(width 0.1)
				(type default)
			)
			(layer "F.Fab")
		)
		(fp_line
			(start 0.120396 0.3048)
			(end 0.120396 0.2794)
			(stroke
				(width 0.1)
				(type default)
			)
			(layer "F.Fab")
		)
		(fp_line
			(start 0.12065 -0.3048)
			(end 0.67945 -0.3048)
			(stroke
				(width 0.1)
				(type default)
			)
			(layer "F.Fab")
		)
		(fp_line
			(start 0.12065 -0.2794)
			(end 0.12065 -0.3048)
			(stroke
				(width 0.1)
				(type default)
			)
			(layer "F.Fab")
		)
		(fp_line
			(start 0.67945 -0.3048)
			(end 0.67945 0.3048)
			(stroke
				(width 0.1)
				(type default)
			)
			(layer "F.Fab")
		)
		(fp_line
			(start 0.67945 0.3048)
			(end 0.120396 0.3048)
			(stroke
				(width 0.1)
				(type default)
			)
			(layer "F.Fab")
		)
		(pad "1" smd circle
			(at -0.40005 0)
			(size 0 0)
			(layers "F.Cu" "F.Mask" "F.Paste")
			(net "P3V3_AUX")
		)
		(pad "2" smd circle
			(at 0.40005 0)
			(size 0 0)
			(layers "F.Cu" "F.Mask" "F.Paste")
			(net "IRQ_UV_DETECT_N")
		)
	)
	(footprint ""
		(layer "F.Cu")
		(at 34.82848 -368.467132 90)
		(property "Reference" "PC366"
			(at 0 0 90)
			(layer "F.SilkS")
			(hide yes)
			(effects
				(font
					(size 1.27 1.27)
				)
			)
		)
		(property "Value" ""
			(at 0 0 90)
			(layer "F.Fab")
			(effects
				(font
					(size 1.27 1.27)
				)
			)
		)
		(duplicate_pad_numbers_are_jumpers no)
		(fp_line
			(start 0.7874 -0.4064)
			(end 0.7874 0.4064)
			(stroke
				(width 0.1524)
				(type default)
			)
			(layer "F.SilkS")
		)
		(fp_line
			(start -0.7874 -0.4064)
			(end 0.7874 -0.4064)
			(stroke
				(width 0.1524)
				(type default)
			)
			(layer "F.SilkS")
		)
		(fp_line
			(start 0.7874 0.4064)
			(end -0.7874 0.4064)
			(stroke
				(width 0.1524)
				(type default)
			)
			(layer "F.SilkS")
		)
		(fp_line
			(start -0.7874 0.4064)
			(end -0.7874 -0.4064)
			(stroke
				(width 0.1524)
				(type default)
			)
			(layer "F.SilkS")
		)
		(fp_line
			(start -0.12065 -0.305054)
			(end -0.12065 -0.2794)
			(stroke
				(width 0.1)
				(type default)
			)
			(layer "F.Fab")
		)
		(fp_line
			(start -0.67945 -0.305054)
			(end -0.12065 -0.305054)
			(stroke
				(width 0.1)
				(type default)
			)
			(layer "F.Fab")
		)
		(fp_line
			(start 0.67945 -0.3048)
			(end 0.67945 0.3048)
			(stroke
				(width 0.1)
				(type default)
			)
			(layer "F.Fab")
		)
		(fp_line
			(start 0.12065 -0.3048)
			(end 0.67945 -0.3048)
			(stroke
				(width 0.1)
				(type default)
			)
			(layer "F.Fab")
		)
		(fp_line
			(start 0.12065 -0.2794)
			(end 0.12065 -0.3048)
			(stroke
				(width 0.1)
				(type default)
			)
			(layer "F.Fab")
		)
		(fp_line
			(start -0.12065 -0.2794)
			(end 0.12065 -0.2794)
			(stroke
				(width 0.1)
				(type default)
			)
			(layer "F.Fab")
		)
		(fp_line
			(start 0.120396 0.2794)
			(end -0.12065 0.2794)
			(stroke
				(width 0.1)
				(type default)
			)
			(layer "F.Fab")
		)
		(fp_line
			(start -0.12065 0.2794)
			(end -0.12065 0.3048)
			(stroke
				(width 0.1)
				(type default)
			)
			(layer "F.Fab")
		)
		(fp_line
			(start 0.67945 0.3048)
			(end 0.120396 0.3048)
			(stroke
				(width 0.1)
				(type default)
			)
			(layer "F.Fab")
		)
		(fp_line
			(start 0.120396 0.3048)
			(end 0.120396 0.2794)
			(stroke
				(width 0.1)
				(type default)
			)
			(layer "F.Fab")
		)
		(fp_line
			(start -0.12065 0.3048)
			(end -0.67945 0.3048)
			(stroke
				(width 0.1)
				(type default)
			)
			(layer "F.Fab")
		)
		(fp_line
			(start -0.67945 0.3048)
			(end -0.67945 -0.305054)
			(stroke
				(width 0.1)
				(type default)
			)
			(layer "F.Fab")
		)
		(pad "1" smd circle
			(at -0.40005 0 90)
			(size 0 0)
			(layers "F.Cu" "F.Mask" "F.Paste")
			(net "PVDDCR_CPU1_P1_VCCS")
		)
		(pad "2" smd circle
			(at 0.40005 0 90)
			(size 0 0)
			(layers "F.Cu" "F.Mask" "F.Paste")
			(net "GND")
		)
	)
	(footprint ""
		(layer "F.Cu")
		(at 165.62451 -123.683014)
		(property "Reference" "R419"
			(at 0 0 0)
			(layer "F.SilkS")
			(hide yes)
			(effects
				(font
					(size 1.27 1.27)
				)
			)
		)
		(property "Value" ""
			(at 0 0 0)
			(layer "F.Fab")
			(effects
				(font
					(size 1.27 1.27)
				)
			)
		)
		(duplicate_pad_numbers_are_jumpers no)
		(fp_line
			(start -0.7874 -0.4064)
			(end 0.7874 -0.4064)
			(stroke
				(width 0.1524)
				(type default)
			)
			(layer "F.SilkS")
		)
		(fp_line
			(start -0.7874 0.4064)
			(end -0.7874 -0.4064)
			(stroke
				(width 0.1524)
				(type default)
			)
			(layer "F.SilkS")
		)
		(fp_line
			(start 0.7874 -0.4064)
			(end 0.7874 0.4064)
			(stroke
				(width 0.1524)
				(type default)
			)
			(layer "F.SilkS")
		)
		(fp_line
			(start 0.7874 0.4064)
			(end -0.7874 0.4064)
			(stroke
				(width 0.1524)
				(type default)
			)
			(layer "F.SilkS")
		)
		(fp_line
			(start -0.67945 -0.305054)
			(end -0.12065 -0.305054)
			(stroke
				(width 0.1)
				(type default)
			)
			(layer "F.Fab")
		)
		(fp_line
			(start -0.67945 0.3048)
			(end -0.67945 -0.305054)
			(stroke
				(width 0.1)
				(type default)
			)
			(layer "F.Fab")
		)
		(fp_line
			(start -0.12065 -0.305054)
			(end -0.12065 -0.2794)
			(stroke
				(width 0.1)
				(type default)
			)
			(layer "F.Fab")
		)
		(fp_line
			(start -0.12065 -0.2794)
			(end 0.12065 -0.2794)
			(stroke
				(width 0.1)
				(type default)
			)
			(layer "F.Fab")
		)
		(fp_line
			(start -0.12065 0.2794)
			(end -0.12065 0.3048)
			(stroke
				(width 0.1)
				(type default)
			)
			(layer "F.Fab")
		)
		(fp_line
			(start -0.12065 0.3048)
			(end -0.67945 0.3048)
			(stroke
				(width 0.1)
				(type default)
			)
			(layer "F.Fab")
		)
		(fp_line
			(start 0.120396 0.2794)
			(end -0.12065 0.2794)
			(stroke
				(width 0.1)
				(type default)
			)
			(layer "F.Fab")
		)
		(fp_line
			(start 0.120396 0.3048)
			(end 0.120396 0.2794)
			(stroke
				(width 0.1)
				(type default)
			)
			(layer "F.Fab")
		)
		(fp_line
			(start 0.12065 -0.3048)
			(end 0.67945 -0.3048)
			(stroke
				(width 0.1)
				(type default)
			)
			(layer "F.Fab")
		)
		(fp_line
			(start 0.12065 -0.2794)
			(end 0.12065 -0.3048)
			(stroke
				(width 0.1)
				(type default)
			)
			(layer "F.Fab")
		)
		(fp_line
			(start 0.67945 -0.3048)
			(end 0.67945 0.3048)
			(stroke
				(width 0.1)
				(type default)
			)
			(layer "F.Fab")
		)
		(fp_line
			(start 0.67945 0.3048)
			(end 0.120396 0.3048)
			(stroke
				(width 0.1)
				(type default)
			)
			(layer "F.Fab")
		)
		(pad "1" smd circle
			(at -0.40005 0)
			(size 0 0)
			(layers "F.Cu" "F.Mask" "F.Paste")
			(net "RST_SRST_PLD_BMC_N")
		)
		(pad "2" smd circle
			(at 0.40005 0)
			(size 0 0)
			(layers "F.Cu" "F.Mask" "F.Paste")
			(net "RST_SRST_PLD_BMC_R_N")
		)
	)
	(footprint ""
		(layer "F.Cu")
		(at 108.346494 -340.085426 -90)
		(property "Reference" "PC141_6"
			(at 0 0 270)
			(layer "F.SilkS")
			(hide yes)
			(effects
				(font
					(size 1.27 1.27)
				)
			)
		)
		(property "Value" ""
			(at 0 0 270)
			(layer "F.Fab")
			(effects
				(font
					(size 1.27 1.27)
				)
			)
		)
		(duplicate_pad_numbers_are_jumpers no)
		(fp_line
			(start -0.7874 0.4064)
			(end -0.7874 -0.4064)
			(stroke
				(width 0.1524)
				(type default)
			)
			(layer "F.SilkS")
		)
		(fp_line
			(start 0.7874 0.4064)
			(end -0.7874 0.4064)
			(stroke
				(width 0.1524)
				(type default)
			)
			(layer "F.SilkS")
		)
		(fp_line
			(start -0.7874 -0.4064)
			(end 0.7874 -0.4064)
			(stroke
				(width 0.1524)
				(type default)
			)
			(layer "F.SilkS")
		)
		(fp_line
			(start 0.7874 -0.4064)
			(end 0.7874 0.4064)
			(stroke
				(width 0.1524)
				(type default)
			)
			(layer "F.SilkS")
		)
		(fp_line
			(start -0.67945 0.3048)
			(end -0.67945 -0.305054)
			(stroke
				(width 0.1)
				(type default)
			)
			(layer "F.Fab")
		)
		(fp_line
			(start -0.12065 0.3048)
			(end -0.67945 0.3048)
			(stroke
				(width 0.1)
				(type default)
			)
			(layer "F.Fab")
		)
		(fp_line
			(start 0.120396 0.3048)
			(end 0.120396 0.2794)
			(stroke
				(width 0.1)
				(type default)
			)
			(layer "F.Fab")
		)
		(fp_line
			(start 0.67945 0.3048)
			(end 0.120396 0.3048)
			(stroke
				(width 0.1)
				(type default)
			)
			(layer "F.Fab")
		)
		(fp_line
			(start -0.12065 0.2794)
			(end -0.12065 0.3048)
			(stroke
				(width 0.1)
				(type default)
			)
			(layer "F.Fab")
		)
		(fp_line
			(start 0.120396 0.2794)
			(end -0.12065 0.2794)
			(stroke
				(width 0.1)
				(type default)
			)
			(layer "F.Fab")
		)
		(fp_line
			(start -0.12065 -0.2794)
			(end 0.12065 -0.2794)
			(stroke
				(width 0.1)
				(type default)
			)
			(layer "F.Fab")
		)
		(fp_line
			(start 0.12065 -0.2794)
			(end 0.12065 -0.3048)
			(stroke
				(width 0.1)
				(type default)
			)
			(layer "F.Fab")
		)
		(fp_line
			(start 0.12065 -0.3048)
			(end 0.67945 -0.3048)
			(stroke
				(width 0.1)
				(type default)
			)
			(layer "F.Fab")
		)
		(fp_line
			(start 0.67945 -0.3048)
			(end 0.67945 0.3048)
			(stroke
				(width 0.1)
				(type default)
			)
			(layer "F.Fab")
		)
		(fp_line
			(start -0.67945 -0.305054)
			(end -0.12065 -0.305054)
			(stroke
				(width 0.1)
				(type default)
			)
			(layer "F.Fab")
		)
		(fp_line
			(start -0.12065 -0.305054)
			(end -0.12065 -0.2794)
			(stroke
				(width 0.1)
				(type default)
			)
			(layer "F.Fab")
		)
		(pad "1" smd circle
			(at -0.40005 0 270)
			(size 0 0)
			(layers "F.Cu" "F.Mask" "F.Paste")
			(net "SW_P12V_AUX_PVDDCR_CPU1_P1_FLT")
		)
		(pad "2" smd circle
			(at 0.40005 0 270)
			(size 0 0)
			(layers "F.Cu" "F.Mask" "F.Paste")
			(net "GND")
		)
	)
	(footprint ""
		(layer "F.Cu")
		(at 177.81016 -389.0518)
		(property "Reference" "R1489"
			(at 0 0 0)
			(layer "F.SilkS")
			(hide yes)
			(effects
				(font
					(size 1.27 1.27)
				)
			)
		)
		(property "Value" ""
			(at 0 0 0)
			(layer "F.Fab")
			(effects
				(font
					(size 1.27 1.27)
				)
			)
		)
		(duplicate_pad_numbers_are_jumpers no)
		(fp_line
			(start -0.32512 -0.175006)
			(end 0.32512 -0.175006)
			(stroke
				(width 0.1)
				(type default)
			)
			(layer "F.Fab")
		)
		(fp_line
			(start -0.32512 0.175006)
			(end -0.32512 -0.175006)
			(stroke
				(width 0.1)
				(type default)
			)
			(layer "F.Fab")
		)
		(fp_line
			(start 0.32512 -0.175006)
			(end 0.32512 0.175006)
			(stroke
				(width 0.1)
				(type default)
			)
			(layer "F.Fab")
		)
		(fp_line
			(start 0.32512 0.175006)
			(end -0.32512 0.175006)
			(stroke
				(width 0.1)
				(type default)
			)
			(layer "F.Fab")
		)
		(pad "1" smd rect
			(at -0.2667 0)
			(size 0.3048 0.381)
			(layers "F.Cu" "F.Mask" "F.Paste")
			(net "P1V8_CPU1_RT_1D")
		)
		(pad "2" smd rect
			(at 0.2667 0 180)
			(size 0.3048 0.381)
			(layers "F.Cu" "F.Mask" "F.Paste")
			(net "JTAG_TMS_RT_CPU1_P2")
		)
	)
)
